(kicad_pcb
	(version 20241229)
	(generator "pcbnew")
	(generator_version "9.0")
	(general
		(thickness 1.61)
		(legacy_teardrops no)
	)
	(paper "A3")
	(title_block
		(title "RDIMM DDR5 Tester")
		(date "2026-05-21")
		(rev "2.2.0")
		(company "Antmicro")
		(comment 9 "footprints 484-488 of 796")
	)
	(layers
		(0 "F.Cu" signal)
		(4 "In1.Cu" power)
		(6 "In2.Cu" mixed)
		(8 "In3.Cu" power)
		(10 "In4.Cu" mixed)
		(12 "In5.Cu" power)
		(14 "In6.Cu" mixed)
		(16 "In7.Cu" power)
		(18 "In8.Cu" power)
		(20 "In9.Cu" mixed)
		(22 "In10.Cu" power)
		(2 "B.Cu" signal)
		(9 "F.Adhes" user "F.Adhesive")
		(11 "B.Adhes" user "B.Adhesive")
		(13 "F.Paste" user)
		(15 "B.Paste" user)
		(5 "F.SilkS" user "F.Silkscreen")
		(7 "B.SilkS" user "B.Silkscreen")
		(1 "F.Mask" user)
		(3 "B.Mask" user)
		(17 "Dwgs.User" user "User.Drawings")
		(19 "Cmts.User" user "User.Comments")
		(21 "Eco1.User" user "User.Eco1")
		(23 "Eco2.User" user "User.Eco2")
		(25 "Edge.Cuts" user)
		(27 "Margin" user)
		(31 "F.CrtYd" user "F.Courtyard")
		(29 "B.CrtYd" user "B.Courtyard")
		(35 "F.Fab" user)
		(33 "B.Fab" user)
	)
	(footprint "antmicro-footprints:C_0402_1005Metric"
		(layer "B.Cu")
		(at 175.65 193.249501 90)
		(descr "Capacitor SMD 0402")
		(tags "capacitor SMD 0402")
		(property "Reference" "C226"
			(at 0.994 0.403501 90)
			(layer "B.SilkS")
			(effects
				(font
					(size 0.7 0.7)
					(thickness 0.15)
				)
				(justify right bottom mirror)
			)
		)
		(property "Value" "C_100n_0402"
			(at -1.022927 -2.155213 90)
			(layer "B.Fab")
			(effects
				(font
					(size 0.7 0.7)
					(thickness 0.15)
				)
				(justify right bottom mirror)
			)
		)
		(property "Datasheet" "https://www.murata.com/products/productdetail?partno=GRM155R61H104KE14%23"
			(at 0 0 90)
			(layer "F.Fab")
			(hide yes)
			(effects
				(font
					(size 1.27 1.27)
					(thickness 0.15)
				)
			)
		)
		(property "Manufacturer" "Murata"
			(at 0 0 90)
			(unlocked yes)
			(layer "B.Fab")
			(hide yes)
			(effects
				(font
					(size 1 1)
					(thickness 0.15)
				)
				(justify mirror)
			)
		)
		(property "MPN" "GRM155R61H104KE14D"
			(at 0 0 90)
			(unlocked yes)
			(layer "B.Fab")
			(hide yes)
			(effects
				(font
					(size 1 1)
					(thickness 0.15)
				)
				(justify mirror)
			)
		)
		(property "Val" "100n"
			(at 0 0 90)
			(unlocked yes)
			(layer "B.Fab")
			(hide yes)
			(effects
				(font
					(size 1 1)
					(thickness 0.15)
				)
				(justify mirror)
			)
		)
		(property "License" "Apache-2.0"
			(at 0 0 90)
			(unlocked yes)
			(layer "B.Fab")
			(hide yes)
			(effects
				(font
					(size 1 1)
					(thickness 0.15)
				)
				(justify mirror)
			)
		)
		(property "Author" "Antmicro"
			(at 0 0 90)
			(unlocked yes)
			(layer "B.Fab")
			(hide yes)
			(effects
				(font
					(size 1 1)
					(thickness 0.15)
				)
				(justify mirror)
			)
		)
		(property "Voltage" "50V"
			(at 0 0 90)
			(unlocked yes)
			(layer "B.Fab")
			(hide yes)
			(effects
				(font
					(size 1 1)
					(thickness 0.15)
				)
				(justify mirror)
			)
		)
		(property "Dielectric" "X5R"
			(at 0 0 90)
			(unlocked yes)
			(layer "B.Fab")
			(hide yes)
			(effects
				(font
					(size 1 1)
					(thickness 0.15)
				)
				(justify mirror)
			)
		)
		(sheetname "/FPGA MGT Interface/")
		(sheetfile "fpga-mgt.kicad_sch")
		(attr smd)
		(fp_rect
			(start -0.925 0.47)
			(end 0.925 -0.47)
			(stroke
				(width 0.05)
				(type default)
			)
			(fill no)
			(layer "B.CrtYd")
		)
		(fp_line
			(start 0.504 -0.248)
			(end -0.494 -0.248)
			(stroke
				(width 0.15)
				(type solid)
			)
			(layer "B.Fab")
		)
		(fp_line
			(start -0.494 -0.248)
			(end -0.494 0.25)
			(stroke
				(width 0.15)
				(type solid)
			)
			(layer "B.Fab")
		)
		(fp_line
			(start 0.504 0.25)
			(end 0.504 -0.248)
			(stroke
				(width 0.15)
				(type solid)
			)
			(layer "B.Fab")
		)
		(fp_line
			(start -0.494 0.25)
			(end 0.504 0.25)
			(stroke
				(width 0.15)
				(type solid)
			)
			(layer "B.Fab")
		)
		(fp_text user "${REFERENCE}"
			(at -0.939 -4.599 270)
			(layer "B.Fab")
			(effects
				(font
					(size 0.7 0.7)
					(thickness 0.15)
				)
				(justify left bottom mirror)
			)
		)
		(fp_text user "License: Apache-2.0"
			(at -0.939 -5.799 270)
			(layer "B.Fab")
			(effects
				(font
					(size 0.7 0.7)
					(thickness 0.15)
				)
				(justify left bottom mirror)
			)
		)
		(fp_text user "Author: Antmicro"
			(at -0.939 -3.399 270)
			(layer "B.Fab")
			(effects
				(font
					(size 0.7 0.7)
					(thickness 0.15)
				)
				(justify left bottom mirror)
			)
		)
		(pad "1" smd roundrect
			(at -0.48 0 90)
			(size 0.59 0.64)
			(layers "B.Cu" "B.Mask" "B.Paste")
			(roundrect_rratio 0.25)
			(net 15 "/FPGA MGT Interface/PCIE.TXD3_P")
			(pintype "passive")
		)
		(pad "2" smd roundrect
			(at 0.48 0 90)
			(size 0.59 0.64)
			(layers "B.Cu" "B.Mask" "B.Paste")
			(roundrect_rratio 0.25)
			(net 16 "/FPGA MGT Interface/GTY_225_TX0_P")
			(pintype "passive")
		)
	)
	(footprint "antmicro-footprints:C_0402_1005Metric_EIA"
		(layer "B.Cu")
		(at 193 162.5 90)
		(descr "Capacitor SMD 0402 (1005 Metric), square (rectangular) end terminal, IPC_7351 nominal, (Body size source: IPC-SM-782 page 76, https://www.pcb-3d.com/wordpress/wp-content/uploads/ipc-sm-782a_amendment_1_and_2.pdf)")
		(tags "capacitor 0402")
		(property "Reference" "C104"
			(at -3.95 0.2 90)
			(layer "B.SilkS")
			(effects
				(font
					(size 0.7 0.7)
					(thickness 0.15)
				)
				(justify right bottom mirror)
			)
		)
		(property "Value" "C_100n_0402"
			(at 0 -1.169 90)
			(layer "B.Fab")
			(effects
				(font
					(size 0.7 0.7)
					(thickness 0.15)
				)
				(justify right bottom mirror)
			)
		)
		(property "Datasheet" "https://www.murata.com/products/productdetail?partno=GRM155R61H104KE14%23"
			(at 0 0 90)
			(layer "F.Fab")
			(hide yes)
			(effects
				(font
					(size 1.27 1.27)
					(thickness 0.15)
				)
			)
		)
		(property "MPN" "GRM155R61H104KE14D"
			(at 0 0 90)
			(unlocked yes)
			(layer "B.Fab")
			(hide yes)
			(effects
				(font
					(size 1 1)
					(thickness 0.15)
				)
				(justify mirror)
			)
		)
		(property "Manufacturer" "Murata"
			(at 0 0 90)
			(unlocked yes)
			(layer "B.Fab")
			(hide yes)
			(effects
				(font
					(size 1 1)
					(thickness 0.15)
				)
				(justify mirror)
			)
		)
		(property "License" "Apache-2.0"
			(at 0 0 90)
			(unlocked yes)
			(layer "B.Fab")
			(hide yes)
			(effects
				(font
					(size 1 1)
					(thickness 0.15)
				)
				(justify mirror)
			)
		)
		(property "Author" "Antmicro"
			(at 0 0 90)
			(unlocked yes)
			(layer "B.Fab")
			(hide yes)
			(effects
				(font
					(size 1 1)
					(thickness 0.15)
				)
				(justify mirror)
			)
		)
		(property "Val" "100n"
			(at 0 0 90)
			(unlocked yes)
			(layer "B.Fab")
			(hide yes)
			(effects
				(font
					(size 1 1)
					(thickness 0.15)
				)
				(justify mirror)
			)
		)
		(property "Voltage" "50V"
			(at 0 0 90)
			(unlocked yes)
			(layer "B.Fab")
			(hide yes)
			(effects
				(font
					(size 1 1)
					(thickness 0.15)
				)
				(justify mirror)
			)
		)
		(property "Dielectric" "X5R"
			(at 0 0 90)
			(unlocked yes)
			(layer "B.Fab")
			(hide yes)
			(effects
				(font
					(size 1 1)
					(thickness 0.15)
				)
				(justify mirror)
			)
		)
		(sheetname "/FPGA power/")
		(sheetfile "fpga-power.kicad_sch")
		(attr smd)
		(fp_rect
			(start -0.95 0.45)
			(end 0.95 -0.45)
			(stroke
				(width 0.05)
				(type default)
			)
			(fill no)
			(layer "B.CrtYd")
		)
		(fp_line
			(start 0.498 -0.248)
			(end -0.5 -0.248)
			(stroke
				(width 0.15)
				(type solid)
			)
			(layer "B.Fab")
		)
		(fp_line
			(start -0.5 -0.248)
			(end -0.5 0.25)
			(stroke
				(width 0.15)
				(type solid)
			)
			(layer "B.Fab")
		)
		(fp_line
			(start 0.498 0.25)
			(end 0.498 -0.248)
			(stroke
				(width 0.15)
				(type solid)
			)
			(layer "B.Fab")
		)
		(fp_line
			(start -0.5 0.25)
			(end 0.498 0.25)
			(stroke
				(width 0.15)
				(type solid)
			)
			(layer "B.Fab")
		)
		(fp_text user "Author: Antmicro"
			(at -0.9656 -5.569 270)
			(layer "B.Fab")
			(effects
				(font
					(size 0.7 0.7)
					(thickness 0.15)
				)
				(justify left bottom mirror)
			)
		)
		(fp_text user "License: Apache-2.0"
			(at -0.9656 -4.369 270)
			(layer "B.Fab")
			(effects
				(font
					(size 0.7 0.7)
					(thickness 0.15)
				)
				(justify left bottom mirror)
			)
		)
		(fp_text user "${REFERENCE}"
			(at -0.9656 -3.169 270)
			(layer "B.Fab")
			(effects
				(font
					(size 0.7 0.7)
					(thickness 0.15)
				)
				(justify left bottom mirror)
			)
		)
		(pad "1" smd roundrect
			(at -0.5 0)
			(size 0.6 0.6)
			(layers "B.Cu" "B.Mask" "B.Paste")
			(roundrect_rratio 0.25)
			(net 1 "GND")
			(pintype "passive")
		)
		(pad "2" smd roundrect
			(at 0.498 0 90)
			(size 0.6 0.6)
			(layers "B.Cu" "B.Mask" "B.Paste")
			(roundrect_rratio 0.25)
			(net 172 "+1V2_MGTAVTT")
			(pintype "passive")
		)
	)
	(footprint "antmicro-footprints:R_0402_1005Metric"
		(layer "B.Cu")
		(at 215.1 183.285 90)
		(descr "Resistor SMD 0402")
		(tags "resistor SMD 0402")
		(property "Reference" "R186"
			(at -0.865 -0.6 90)
			(layer "B.SilkS")
			(effects
				(font
					(size 0.7 0.7)
					(thickness 0.15)
				)
				(justify right bottom mirror)
			)
		)
		(property "Value" "R_0R_0402"
			(at -1.011843 -1.772047 90)
			(layer "B.Fab")
			(effects
				(font
					(size 0.7 0.7)
					(thickness 0.15)
				)
				(justify right bottom mirror)
			)
		)
		(property "Datasheet" "https://industrial.panasonic.com/cdbs/www-data/pdf/RDA0000/AOA0000C301.pdf"
			(at 0 0 90)
			(layer "F.Fab")
			(hide yes)
			(effects
				(font
					(size 1.27 1.27)
					(thickness 0.15)
				)
			)
		)
		(property "MPN" "ERJ2GE0R00X"
			(at 0 0 90)
			(unlocked yes)
			(layer "B.Fab")
			(hide yes)
			(effects
				(font
					(size 1 1)
					(thickness 0.15)
				)
				(justify mirror)
			)
		)
		(property "Manufacturer" "Panasonic"
			(at 0 0 90)
			(unlocked yes)
			(layer "B.Fab")
			(hide yes)
			(effects
				(font
					(size 1 1)
					(thickness 0.15)
				)
				(justify mirror)
			)
		)
		(property "License" "Apache-2.0"
			(at 0 0 90)
			(unlocked yes)
			(layer "B.Fab")
			(hide yes)
			(effects
				(font
					(size 1 1)
					(thickness 0.15)
				)
				(justify mirror)
			)
		)
		(property "Author" "Antmicro"
			(at 0 0 90)
			(unlocked yes)
			(layer "B.Fab")
			(hide yes)
			(effects
				(font
					(size 1 1)
					(thickness 0.15)
				)
				(justify mirror)
			)
		)
		(property "Val" "0R"
			(at 0 0 90)
			(unlocked yes)
			(layer "B.Fab")
			(hide yes)
			(effects
				(font
					(size 1 1)
					(thickness 0.15)
				)
				(justify mirror)
			)
		)
		(property "Tolerance" "~"
			(at 0 0 90)
			(unlocked yes)
			(layer "B.Fab")
			(hide yes)
			(effects
				(font
					(size 1 1)
					(thickness 0.15)
				)
				(justify mirror)
			)
		)
		(property "Current" "1A"
			(at 0 0 90)
			(unlocked yes)
			(layer "B.Fab")
			(hide yes)
			(effects
				(font
					(size 1 1)
					(thickness 0.15)
				)
				(justify mirror)
			)
		)
		(sheetname "/Supply/DC-DC VCCINT/")
		(sheetfile "dc-dc-vccint.kicad_sch")
		(attr smd exclude_from_bom dnp)
		(fp_rect
			(start -0.925 0.47)
			(end 0.925 -0.47)
			(stroke
				(width 0.05)
				(type default)
			)
			(fill no)
			(layer "B.CrtYd")
		)
		(fp_rect
			(start -0.5 0.25)
			(end 0.5 -0.25)
			(stroke
				(width 0.15)
				(type solid)
			)
			(fill no)
			(layer "B.Fab")
		)
		(fp_text user "License: Apache-2.0"
			(at -0.95 -5.169 270)
			(layer "B.Fab")
			(effects
				(font
					(size 0.7 0.7)
					(thickness 0.15)
				)
				(justify left bottom mirror)
			)
		)
		(fp_text user "${REFERENCE}"
			(at -0.95 -3.168 270)
			(layer "B.Fab")
			(effects
				(font
					(size 0.7 0.7)
					(thickness 0.15)
				)
				(justify left bottom mirror)
			)
		)
		(fp_text user "Author: Antmicro"
			(at -0.95 -4.169 270)
			(layer "B.Fab")
			(effects
				(font
					(size 0.7 0.7)
					(thickness 0.15)
				)
				(justify left bottom mirror)
			)
		)
		(pad "1" smd roundrect
			(at -0.48 0 90)
			(size 0.59 0.64)
			(layers "B.Cu" "B.Mask" "B.Paste")
			(roundrect_rratio 0.25)
			(net 724 "/Supply/DC-DC VCCINT/TAKE0")
			(pintype "passive")
		)
		(pad "2" smd roundrect
			(at 0.48 0 90)
			(size 0.59 0.64)
			(layers "B.Cu" "B.Mask" "B.Paste")
			(roundrect_rratio 0.25)
			(net 721 "/Supply/DC-DC VCCINT/PASS0")
			(pintype "passive")
		)
	)
	(footprint "antmicro-footprints:C_0402_1005Metric"
		(layer "B.Cu")
		(at 180.510001 167.45 90)
		(descr "Capacitor SMD 0402")
		(tags "capacitor SMD 0402")
		(property "Reference" "C244"
			(at -4 -0.134 90)
			(layer "B.SilkS")
			(effects
				(font
					(size 0.7 0.7)
					(thickness 0.15)
				)
				(justify right bottom mirror)
			)
		)
		(property "Value" "C_100n_0402"
			(at -1.022927 -2.155213 90)
			(layer "B.Fab")
			(effects
				(font
					(size 0.7 0.7)
					(thickness 0.15)
				)
				(justify right bottom mirror)
			)
		)
		(property "Datasheet" "https://www.murata.com/products/productdetail?partno=GRM155R61H104KE14%23"
			(at 0 0 90)
			(layer "F.Fab")
			(hide yes)
			(effects
				(font
					(size 1.27 1.27)
					(thickness 0.15)
				)
			)
		)
		(property "Manufacturer" "Murata"
			(at 0 0 90)
			(unlocked yes)
			(layer "B.Fab")
			(hide yes)
			(effects
				(font
					(size 1 1)
					(thickness 0.15)
				)
				(justify mirror)
			)
		)
		(property "MPN" "GRM155R61H104KE14D"
			(at 0 0 90)
			(unlocked yes)
			(layer "B.Fab")
			(hide yes)
			(effects
				(font
					(size 1 1)
					(thickness 0.15)
				)
				(justify mirror)
			)
		)
		(property "Val" "100n"
			(at 0 0 90)
			(unlocked yes)
			(layer "B.Fab")
			(hide yes)
			(effects
				(font
					(size 1 1)
					(thickness 0.15)
				)
				(justify mirror)
			)
		)
		(property "License" "Apache-2.0"
			(at 0 0 90)
			(unlocked yes)
			(layer "B.Fab")
			(hide yes)
			(effects
				(font
					(size 1 1)
					(thickness 0.15)
				)
				(justify mirror)
			)
		)
		(property "Author" "Antmicro"
			(at 0 0 90)
			(unlocked yes)
			(layer "B.Fab")
			(hide yes)
			(effects
				(font
					(size 1 1)
					(thickness 0.15)
				)
				(justify mirror)
			)
		)
		(property "Voltage" "50V"
			(at 0 0 90)
			(unlocked yes)
			(layer "B.Fab")
			(hide yes)
			(effects
				(font
					(size 1 1)
					(thickness 0.15)
				)
				(justify mirror)
			)
		)
		(property "Dielectric" "X5R"
			(at 0 0 90)
			(unlocked yes)
			(layer "B.Fab")
			(hide yes)
			(effects
				(font
					(size 1 1)
					(thickness 0.15)
				)
				(justify mirror)
			)
		)
		(sheetname "/FPGA MGT Interface/")
		(sheetfile "fpga-mgt.kicad_sch")
		(attr smd)
		(fp_rect
			(start -0.925 0.47)
			(end 0.925 -0.47)
			(stroke
				(width 0.05)
				(type default)
			)
			(fill no)
			(layer "B.CrtYd")
		)
		(fp_line
			(start 0.504 -0.248)
			(end -0.494 -0.248)
			(stroke
				(width 0.15)
				(type solid)
			)
			(layer "B.Fab")
		)
		(fp_line
			(start -0.494 -0.248)
			(end -0.494 0.25)
			(stroke
				(width 0.15)
				(type solid)
			)
			(layer "B.Fab")
		)
		(fp_line
			(start 0.504 0.25)
			(end 0.504 -0.248)
			(stroke
				(width 0.15)
				(type solid)
			)
			(layer "B.Fab")
		)
		(fp_line
			(start -0.494 0.25)
			(end 0.504 0.25)
			(stroke
				(width 0.15)
				(type solid)
			)
			(layer "B.Fab")
		)
		(fp_text user "Author: Antmicro"
			(at -0.939 -3.399 270)
			(layer "B.Fab")
			(effects
				(font
					(size 0.7 0.7)
					(thickness 0.15)
				)
				(justify left bottom mirror)
			)
		)
		(fp_text user "License: Apache-2.0"
			(at -0.939 -5.799 270)
			(layer "B.Fab")
			(effects
				(font
					(size 0.7 0.7)
					(thickness 0.15)
				)
				(justify left bottom mirror)
			)
		)
		(fp_text user "${REFERENCE}"
			(at -0.939 -4.599 270)
			(layer "B.Fab")
			(effects
				(font
					(size 0.7 0.7)
					(thickness 0.15)
				)
				(justify left bottom mirror)
			)
		)
		(pad "1" smd roundrect
			(at -0.48 0 90)
			(size 0.59 0.64)
			(layers "B.Cu" "B.Mask" "B.Paste")
			(roundrect_rratio 0.25)
			(net 381 "/FPGA MGT Interface/HDMI_OUT.CLK_P")
			(pintype "passive")
		)
		(pad "2" smd roundrect
			(at 0.48 0 90)
			(size 0.59 0.64)
			(layers "B.Cu" "B.Mask" "B.Paste")
			(roundrect_rratio 0.25)
			(net 382 "/FPGA MGT Interface/HDMI_FPGA.TX_CLK_P")
			(pintype "passive")
		)
	)
	(footprint "antmicro-footprints:C_0402_1005Metric_EIA"
		(layer "B.Cu")
		(at 192 143.5 90)
		(descr "Capacitor SMD 0402 (1005 Metric), square (rectangular) end terminal, IPC_7351 nominal, (Body size source: IPC-SM-782 page 76, https://www.pcb-3d.com/wordpress/wp-content/uploads/ipc-sm-782a_amendment_1_and_2.pdf)")
		(tags "capacitor 0402")
		(property "Reference" "C49"
			(at -1.05 1.475 90)
			(layer "B.SilkS")
			(effects
				(font
					(size 0.7 0.7)
					(thickness 0.15)
				)
				(justify right bottom mirror)
			)
		)
		(property "Value" "C_10u_10V_0402"
			(at 0 -1.169 90)
			(layer "B.Fab")
			(effects
				(font
					(size 0.7 0.7)
					(thickness 0.15)
				)
				(justify right bottom mirror)
			)
		)
		(property "Datasheet" "https://www.murata.com/products/productdetail?partno=GRM155R61A106ME11%23"
			(at 0 0 90)
			(layer "F.Fab")
			(hide yes)
			(effects
				(font
					(size 1.27 1.27)
					(thickness 0.15)
				)
			)
		)
		(property "MPN" "GRM155R61A106ME11D"
			(at 0 0 90)
			(unlocked yes)
			(layer "B.Fab")
			(hide yes)
			(effects
				(font
					(size 1 1)
					(thickness 0.15)
				)
				(justify mirror)
			)
		)
		(property "Manufacturer" "Murata"
			(at 0 0 90)
			(unlocked yes)
			(layer "B.Fab")
			(hide yes)
			(effects
				(font
					(size 1 1)
					(thickness 0.15)
				)
				(justify mirror)
			)
		)
		(property "License" "Apache-2.0"
			(at 0 0 90)
			(unlocked yes)
			(layer "B.Fab")
			(hide yes)
			(effects
				(font
					(size 1 1)
					(thickness 0.15)
				)
				(justify mirror)
			)
		)
		(property "Author" "Antmicro"
			(at 0 0 90)
			(unlocked yes)
			(layer "B.Fab")
			(hide yes)
			(effects
				(font
					(size 1 1)
					(thickness 0.15)
				)
				(justify mirror)
			)
		)
		(property "Val" "10u"
			(at 0 0 90)
			(unlocked yes)
			(layer "B.Fab")
			(hide yes)
			(effects
				(font
					(size 1 1)
					(thickness 0.15)
				)
				(justify mirror)
			)
		)
		(property "Voltage" "10V"
			(at 0 0 90)
			(unlocked yes)
			(layer "B.Fab")
			(hide yes)
			(effects
				(font
					(size 1 1)
					(thickness 0.15)
				)
				(justify mirror)
			)
		)
		(property "Dielectric" "X5R"
			(at 0 0 90)
			(unlocked yes)
			(layer "B.Fab")
			(hide yes)
			(effects
				(font
					(size 1 1)
					(thickness 0.15)
				)
				(justify mirror)
			)
		)
		(sheetname "/FPGA power/")
		(sheetfile "fpga-power.kicad_sch")
		(attr smd)
		(fp_rect
			(start -0.95 0.45)
			(end 0.95 -0.45)
			(stroke
				(width 0.05)
				(type default)
			)
			(fill no)
			(layer "B.CrtYd")
		)
		(fp_line
			(start 0.498 -0.248)
			(end -0.5 -0.248)
			(stroke
				(width 0.15)
				(type solid)
			)
			(layer "B.Fab")
		)
		(fp_line
			(start -0.5 -0.248)
			(end -0.5 0.25)
			(stroke
				(width 0.15)
				(type solid)
			)
			(layer "B.Fab")
		)
		(fp_line
			(start 0.498 0.25)
			(end 0.498 -0.248)
			(stroke
				(width 0.15)
				(type solid)
			)
			(layer "B.Fab")
		)
		(fp_line
			(start -0.5 0.25)
			(end 0.498 0.25)
			(stroke
				(width 0.15)
				(type solid)
			)
			(layer "B.Fab")
		)
		(fp_text user "${REFERENCE}"
			(at -0.9656 -3.169 270)
			(layer "B.Fab")
			(effects
				(font
					(size 0.7 0.7)
					(thickness 0.15)
				)
				(justify left bottom mirror)
			)
		)
		(fp_text user "License: Apache-2.0"
			(at -0.9656 -4.369 270)
			(layer "B.Fab")
			(effects
				(font
					(size 0.7 0.7)
					(thickness 0.15)
				)
				(justify left bottom mirror)
			)
		)
		(fp_text user "Author: Antmicro"
			(at -0.9656 -5.569 270)
			(layer "B.Fab")
			(effects
				(font
					(size 0.7 0.7)
					(thickness 0.15)
				)
				(justify left bottom mirror)
			)
		)
		(pad "1" smd roundrect
			(at -0.5 0)
			(size 0.6 0.6)
			(layers "B.Cu" "B.Mask" "B.Paste")
			(roundrect_rratio 0.25)
			(net 1 "GND")
			(pintype "passive")
		)
		(pad "2" smd roundrect
			(at 0.498 0 90)
			(size 0.6 0.6)
			(layers "B.Cu" "B.Mask" "B.Paste")
			(roundrect_rratio 0.25)
			(net 687 "VDDQ")
			(pintype "passive")
		)
	)
)
